(kicad_pcb
	(version 20260206)
	(generator "pcbnew")
	(generator_version "10.0")
	(general
		(thickness 1.6)
		(legacy_teardrops no)
	)
	(paper "A4")
	(title_block
		(title "v1-chassis-manager — T6M_CM_d_v01_1031_1645.brd")
		(comment 1 "Open CloudServer (Microsoft) / footprints 2463-2472 of 2512")
	)
	(layers
		(0 "F.Cu" signal "TOP")
		(4 "In1.Cu" signal "GND1")
		(6 "In2.Cu" signal "IN1")
		(8 "In3.Cu" signal "VCC1")
		(10 "In4.Cu" signal "VCC2")
		(12 "In5.Cu" signal "GND2")
		(14 "In6.Cu" signal "IN2")
		(16 "In7.Cu" signal "IN3")
		(18 "In8.Cu" signal "GND3")
		(2 "B.Cu" signal "BOTTOM")
		(9 "F.Adhes" user "F.Adhesive")
		(11 "B.Adhes" user "B.Adhesive")
		(13 "F.Paste" user "Package Geometry/Pastemask Top")
		(15 "B.Paste" user "Package Geometry/Pastemask Bottom")
		(5 "F.SilkS" user "Ref Des/Silkscreen Top")
		(7 "B.SilkS" user "Ref Des/Silkscreen Bottom")
		(1 "F.Mask" user "Board Geometry/Soldermask Top")
		(3 "B.Mask" user "Board Geometry/Soldermask Bottom")
		(17 "Dwgs.User" user "User.Drawings")
		(19 "Cmts.User" user "User.Comments")
		(21 "Eco1.User" user "User.Eco1")
		(23 "Eco2.User" user "User.Eco2")
		(25 "Edge.Cuts" user "Board Geometry/Outline")
		(27 "Margin" user)
		(31 "F.CrtYd" user "Package Geometry/Place Bound Top")
		(29 "B.CrtYd" user "Package Geometry/Place Bound Bottom")
		(35 "F.Fab" user "Ref Des/Assembly Top")
		(33 "B.Fab" user "Ref Des/Assembly Bottom")
	)
	(footprint ""
		(layer "B.Cu")
		(at 142.07236 -176.061624 180)
		(property "Reference" "R733"
			(at 1.287272 0.298196 0)
			(unlocked yes)
			(layer "B.SilkS")
			(effects
				(font
					(size 0.7874 0.5842)
					(thickness 0.1524)
				)
				(justify left mirror)
			)
		)
		(property "Value" ""
			(at 0 0 0)
			(layer "B.Fab")
			(effects
				(font
					(size 1.27 1.27)
				)
				(justify mirror)
			)
		)
		(duplicate_pad_numbers_are_jumpers no)
		(fp_line
			(start 0.7874 0.4064)
			(end 0.7874 -0.4064)
			(stroke
				(width 0.1524)
				(type default)
			)
			(layer "B.SilkS")
		)
		(fp_line
			(start 0.7874 -0.4064)
			(end -0.7874 -0.4064)
			(stroke
				(width 0.1524)
				(type default)
			)
			(layer "B.SilkS")
		)
		(fp_line
			(start -0.7874 0.4064)
			(end 0.7874 0.4064)
			(stroke
				(width 0.1524)
				(type default)
			)
			(layer "B.SilkS")
		)
		(fp_line
			(start -0.7874 -0.4064)
			(end -0.7874 0.4064)
			(stroke
				(width 0.1524)
				(type default)
			)
			(layer "B.SilkS")
		)
		(fp_poly
			(pts
				(xy 0.508 0.2794) (xy 0.508 0.2286) (xy 0.635 0.2286) (xy 0.635 -0.254) (xy 0.5334 -0.254) (xy 0.5334 -0.2794)
				(xy -0.5334 -0.2794) (xy -0.5334 -0.254) (xy -0.635 -0.254) (xy -0.635 0.254) (xy -0.5334 0.254)
				(xy -0.5334 0.2794)
			)
			(stroke
				(width 0)
				(type default)
			)
			(fill no)
			(layer "B.CrtYd")
		)
		(pad "1" smd rect
			(at -0.40005 0)
			(size 0.4572 0.508)
			(layers "B.Cu" "B.Mask" "B.Paste")
			(net "T10_NODE2_EN")
		)
		(pad "2" smd rect
			(at 0.40005 0)
			(size 0.4572 0.508)
			(layers "B.Cu" "B.Mask" "B.Paste")
			(net "P5V_NODE1")
		)
	)
	(footprint ""
		(layer "B.Cu")
		(at 70.690994 -121.063258 90)
		(property "Reference" "R254"
			(at -7.391146 9.837928 270)
			(unlocked yes)
			(layer "B.SilkS")
			(effects
				(font
					(size 0.7874 0.5842)
					(thickness 0.1524)
				)
				(justify left mirror)
			)
		)
		(property "Value" ""
			(at 0 0 90)
			(layer "B.Fab")
			(effects
				(font
					(size 1.27 1.27)
				)
				(justify mirror)
			)
		)
		(duplicate_pad_numbers_are_jumpers no)
		(fp_line
			(start 0.7874 -0.4064)
			(end -0.7874 -0.4064)
			(stroke
				(width 0.1524)
				(type default)
			)
			(layer "B.SilkS")
		)
		(fp_line
			(start -0.7874 -0.4064)
			(end -0.7874 0.4064)
			(stroke
				(width 0.1524)
				(type default)
			)
			(layer "B.SilkS")
		)
		(fp_line
			(start 0.7874 0.4064)
			(end 0.7874 -0.4064)
			(stroke
				(width 0.1524)
				(type default)
			)
			(layer "B.SilkS")
		)
		(fp_line
			(start -0.7874 0.4064)
			(end 0.7874 0.4064)
			(stroke
				(width 0.1524)
				(type default)
			)
			(layer "B.SilkS")
		)
		(fp_poly
			(pts
				(xy 0.508 0.2794) (xy 0.508 0.2286) (xy 0.635 0.2286) (xy 0.635 -0.254) (xy 0.5334 -0.254) (xy 0.5334 -0.2794)
				(xy -0.5334 -0.2794) (xy -0.5334 -0.254) (xy -0.635 -0.254) (xy -0.635 0.254) (xy -0.5334 0.254)
				(xy -0.5334 0.2794)
			)
			(stroke
				(width 0)
				(type default)
			)
			(fill no)
			(layer "B.CrtYd")
		)
		(pad "1" smd rect
			(at -0.40005 0 270)
			(size 0.4572 0.508)
			(layers "B.Cu" "B.Mask" "B.Paste")
			(net "FM_CPLD_NODE1_BMC_PERST_L")
		)
		(pad "2" smd rect
			(at 0.40005 0 270)
			(size 0.4572 0.508)
			(layers "B.Cu" "B.Mask" "B.Paste")
			(net "RST_BMC_NODE1_PERST_L")
		)
	)
	(footprint ""
		(layer "B.Cu")
		(at 164.021008 -168.149524 -90)
		(property "Reference" "R1061"
			(at 4.91871 -1.245362 270)
			(unlocked yes)
			(layer "B.SilkS")
			(effects
				(font
					(size 0.7874 0.5842)
					(thickness 0.1524)
				)
				(justify left mirror)
			)
		)
		(property "Value" ""
			(at 0 0 90)
			(layer "B.Fab")
			(effects
				(font
					(size 1.27 1.27)
				)
				(justify mirror)
			)
		)
		(duplicate_pad_numbers_are_jumpers no)
		(fp_line
			(start -0.7874 0.4064)
			(end 0.7874 0.4064)
			(stroke
				(width 0.1524)
				(type default)
			)
			(layer "B.SilkS")
		)
		(fp_line
			(start 0.7874 0.4064)
			(end 0.7874 -0.4064)
			(stroke
				(width 0.1524)
				(type default)
			)
			(layer "B.SilkS")
		)
		(fp_line
			(start -0.7874 -0.4064)
			(end -0.7874 0.4064)
			(stroke
				(width 0.1524)
				(type default)
			)
			(layer "B.SilkS")
		)
		(fp_line
			(start 0.7874 -0.4064)
			(end -0.7874 -0.4064)
			(stroke
				(width 0.1524)
				(type default)
			)
			(layer "B.SilkS")
		)
		(fp_poly
			(pts
				(xy 0.508 0.2794) (xy 0.508 0.2286) (xy 0.635 0.2286) (xy 0.635 -0.254) (xy 0.5334 -0.254) (xy 0.5334 -0.2794)
				(xy -0.5334 -0.2794) (xy -0.5334 -0.254) (xy -0.635 -0.254) (xy -0.635 0.254) (xy -0.5334 0.254)
				(xy -0.5334 0.2794)
			)
			(stroke
				(width 0)
				(type default)
			)
			(fill no)
			(layer "B.CrtYd")
		)
		(pad "1" smd rect
			(at -0.40005 0 90)
			(size 0.4572 0.508)
			(layers "B.Cu" "B.Mask" "B.Paste")
			(net "CPLD_UART_RI_P3_LS_N")
		)
		(pad "2" smd rect
			(at 0.40005 0 90)
			(size 0.4572 0.508)
			(layers "B.Cu" "B.Mask" "B.Paste")
			(net "CPLD_UART_RI_P3_N")
		)
	)
	(footprint ""
		(layer "B.Cu")
		(at 137.970006 -39.47541 180)
		(property "Reference" "R1190"
			(at 4.172458 -18.307812 0)
			(unlocked yes)
			(layer "B.SilkS")
			(effects
				(font
					(size 0.7874 0.5842)
					(thickness 0.1524)
				)
				(justify left mirror)
			)
		)
		(property "Value" ""
			(at 0 0 0)
			(layer "B.Fab")
			(effects
				(font
					(size 1.27 1.27)
				)
				(justify mirror)
			)
		)
		(duplicate_pad_numbers_are_jumpers no)
		(fp_line
			(start 0.7874 0.4064)
			(end 0.7874 -0.4064)
			(stroke
				(width 0.1524)
				(type default)
			)
			(layer "B.SilkS")
		)
		(fp_line
			(start 0.7874 -0.4064)
			(end -0.7874 -0.4064)
			(stroke
				(width 0.1524)
				(type default)
			)
			(layer "B.SilkS")
		)
		(fp_line
			(start -0.7874 0.4064)
			(end 0.7874 0.4064)
			(stroke
				(width 0.1524)
				(type default)
			)
			(layer "B.SilkS")
		)
		(fp_line
			(start -0.7874 -0.4064)
			(end -0.7874 0.4064)
			(stroke
				(width 0.1524)
				(type default)
			)
			(layer "B.SilkS")
		)
		(fp_poly
			(pts
				(xy 0.508 0.2794) (xy 0.508 0.2286) (xy 0.635 0.2286) (xy 0.635 -0.254) (xy 0.5334 -0.254) (xy 0.5334 -0.2794)
				(xy -0.5334 -0.2794) (xy -0.5334 -0.254) (xy -0.635 -0.254) (xy -0.635 0.254) (xy -0.5334 0.254)
				(xy -0.5334 0.2794)
			)
			(stroke
				(width 0)
				(type default)
			)
			(fill no)
			(layer "B.CrtYd")
		)
		(pad "1" smd rect
			(at -0.40005 0)
			(size 0.4572 0.508)
			(layers "B.Cu" "B.Mask" "B.Paste")
			(net "SIO_JTAG_CPLD2_TMS_R")
		)
		(pad "2" smd rect
			(at 0.40005 0)
			(size 0.4572 0.508)
			(layers "B.Cu" "B.Mask" "B.Paste")
			(net "SIO_JTAG_CPLD2_TMS")
		)
	)
	(footprint ""
		(layer "B.Cu")
		(at 114.721132 -166.980362)
		(property "Reference" "R1243"
			(at -1.797812 -0.2413 0)
			(unlocked yes)
			(layer "B.SilkS")
			(effects
				(font
					(size 0.7874 0.5842)
					(thickness 0.1524)
				)
				(justify left mirror)
			)
		)
		(property "Value" ""
			(at 0 0 0)
			(layer "B.Fab")
			(effects
				(font
					(size 1.27 1.27)
				)
				(justify mirror)
			)
		)
		(duplicate_pad_numbers_are_jumpers no)
		(fp_line
			(start -0.7874 -0.4064)
			(end -0.7874 0.4064)
			(stroke
				(width 0.1524)
				(type default)
			)
			(layer "B.SilkS")
		)
		(fp_line
			(start -0.7874 0.4064)
			(end 0.7874 0.4064)
			(stroke
				(width 0.1524)
				(type default)
			)
			(layer "B.SilkS")
		)
		(fp_line
			(start 0.7874 -0.4064)
			(end -0.7874 -0.4064)
			(stroke
				(width 0.1524)
				(type default)
			)
			(layer "B.SilkS")
		)
		(fp_line
			(start 0.7874 0.4064)
			(end 0.7874 -0.4064)
			(stroke
				(width 0.1524)
				(type default)
			)
			(layer "B.SilkS")
		)
		(fp_poly
			(pts
				(xy 0.508 0.2794) (xy 0.508 0.2286) (xy 0.635 0.2286) (xy 0.635 -0.254) (xy 0.5334 -0.254) (xy 0.5334 -0.2794)
				(xy -0.5334 -0.2794) (xy -0.5334 -0.254) (xy -0.635 -0.254) (xy -0.635 0.254) (xy -0.5334 0.254)
				(xy -0.5334 0.2794)
			)
			(stroke
				(width 0)
				(type default)
			)
			(fill no)
			(layer "B.CrtYd")
		)
		(pad "1" smd rect
			(at -0.40005 0 180)
			(size 0.4572 0.508)
			(layers "B.Cu" "B.Mask" "B.Paste")
			(net "GND")
		)
		(pad "2" smd rect
			(at 0.40005 0 180)
			(size 0.4572 0.508)
			(layers "B.Cu" "B.Mask" "B.Paste")
			(net "PSU1_HUB_EN")
		)
	)
	(footprint ""
		(layer "B.Cu")
		(at 66.524886 -137.986262 180)
		(property "Reference" "C292"
			(at 37.331396 -55.008526 0)
			(unlocked yes)
			(layer "B.SilkS")
			(effects
				(font
					(size 0.7874 0.5842)
					(thickness 0.1524)
				)
				(justify left mirror)
			)
		)
		(property "Value" ""
			(at 0 0 0)
			(layer "B.Fab")
			(effects
				(font
					(size 1.27 1.27)
				)
				(justify mirror)
			)
		)
		(duplicate_pad_numbers_are_jumpers no)
		(fp_line
			(start 0.7874 0.4064)
			(end 0.7874 -0.4064)
			(stroke
				(width 0.1524)
				(type default)
			)
			(layer "B.SilkS")
		)
		(fp_line
			(start 0.7874 -0.4064)
			(end -0.7874 -0.4064)
			(stroke
				(width 0.1524)
				(type default)
			)
			(layer "B.SilkS")
		)
		(fp_line
			(start 0 0.381)
			(end 0 -0.381)
			(stroke
				(width 0.1524)
				(type default)
			)
			(layer "B.SilkS")
		)
		(fp_line
			(start -0.7874 0.4064)
			(end 0.7874 0.4064)
			(stroke
				(width 0.1524)
				(type default)
			)
			(layer "B.SilkS")
		)
		(fp_line
			(start -0.7874 -0.4064)
			(end -0.7874 0.4064)
			(stroke
				(width 0.1524)
				(type default)
			)
			(layer "B.SilkS")
		)
		(fp_poly
			(pts
				(xy 0.5334 0.254) (xy 0.635 0.254) (xy 0.635 0.2286) (xy 0.635 -0.254) (xy 0.5334 -0.254) (xy 0.5334 -0.2794)
				(xy -0.5334 -0.2794) (xy -0.5334 -0.254) (xy -0.635 -0.254) (xy -0.635 0.254) (xy -0.5334 0.254)
				(xy -0.5334 0.2794) (xy 0.508 0.2794) (xy 0.5334 0.2794)
			)
			(stroke
				(width 0)
				(type default)
			)
			(fill no)
			(layer "B.CrtYd")
		)
		(pad "1" smd rect
			(at -0.40005 0)
			(size 0.4572 0.508)
			(layers "B.Cu" "B.Mask" "B.Paste")
			(net "P1V26_BMC_NODE1")
		)
		(pad "2" smd rect
			(at 0.40005 0)
			(size 0.4572 0.508)
			(layers "B.Cu" "B.Mask" "B.Paste")
			(net "GND")
		)
	)
	(footprint ""
		(layer "B.Cu")
		(at 61.591952 -95.7961)
		(property "Reference" "R61"
			(at -3.892296 -7.642352 0)
			(unlocked yes)
			(layer "B.SilkS")
			(effects
				(font
					(size 0.7874 0.5842)
					(thickness 0.1524)
				)
				(justify left mirror)
			)
		)
		(property "Value" ""
			(at 0 0 0)
			(layer "B.Fab")
			(effects
				(font
					(size 1.27 1.27)
				)
				(justify mirror)
			)
		)
		(duplicate_pad_numbers_are_jumpers no)
		(fp_line
			(start -0.7874 -0.4064)
			(end -0.7874 0.4064)
			(stroke
				(width 0.1524)
				(type default)
			)
			(layer "B.SilkS")
		)
		(fp_line
			(start -0.7874 0.4064)
			(end 0.7874 0.4064)
			(stroke
				(width 0.1524)
				(type default)
			)
			(layer "B.SilkS")
		)
		(fp_line
			(start 0.7874 -0.4064)
			(end -0.7874 -0.4064)
			(stroke
				(width 0.1524)
				(type default)
			)
			(layer "B.SilkS")
		)
		(fp_line
			(start 0.7874 0.4064)
			(end 0.7874 -0.4064)
			(stroke
				(width 0.1524)
				(type default)
			)
			(layer "B.SilkS")
		)
		(fp_poly
			(pts
				(xy 0.508 0.2794) (xy 0.508 0.2286) (xy 0.635 0.2286) (xy 0.635 -0.254) (xy 0.5334 -0.254) (xy 0.5334 -0.2794)
				(xy -0.5334 -0.2794) (xy -0.5334 -0.254) (xy -0.635 -0.254) (xy -0.635 0.254) (xy -0.5334 0.254)
				(xy -0.5334 0.2794)
			)
			(stroke
				(width 0)
				(type default)
			)
			(fill no)
			(layer "B.CrtYd")
		)
		(pad "1" smd rect
			(at -0.40005 0 180)
			(size 0.4572 0.508)
			(layers "B.Cu" "B.Mask" "B.Paste")
			(net "LPC_CPU_NODE1_LAD2")
		)
		(pad "2" smd rect
			(at 0.40005 0 180)
			(size 0.4572 0.508)
			(layers "B.Cu" "B.Mask" "B.Paste")
			(net "LPC_CPU_NODE1_LAD2_R")
		)
	)
	(footprint ""
		(layer "B.Cu")
		(at 48.758602 -158.250382 180)
		(property "Reference" "C398"
			(at 11.821922 3.479292 0)
			(unlocked yes)
			(layer "B.SilkS")
			(effects
				(font
					(size 0.7874 0.5842)
					(thickness 0.1524)
				)
				(justify left mirror)
			)
		)
		(property "Value" ""
			(at 0 0 0)
			(layer "B.Fab")
			(effects
				(font
					(size 1.27 1.27)
				)
				(justify mirror)
			)
		)
		(duplicate_pad_numbers_are_jumpers no)
		(fp_line
			(start 0.7874 0.4064)
			(end 0.7874 -0.4064)
			(stroke
				(width 0.1524)
				(type default)
			)
			(layer "B.SilkS")
		)
		(fp_line
			(start 0.7874 -0.4064)
			(end -0.7874 -0.4064)
			(stroke
				(width 0.1524)
				(type default)
			)
			(layer "B.SilkS")
		)
		(fp_line
			(start 0 0.381)
			(end 0 -0.381)
			(stroke
				(width 0.1524)
				(type default)
			)
			(layer "B.SilkS")
		)
		(fp_line
			(start -0.7874 0.4064)
			(end 0.7874 0.4064)
			(stroke
				(width 0.1524)
				(type default)
			)
			(layer "B.SilkS")
		)
		(fp_line
			(start -0.7874 -0.4064)
			(end -0.7874 0.4064)
			(stroke
				(width 0.1524)
				(type default)
			)
			(layer "B.SilkS")
		)
		(fp_poly
			(pts
				(xy 0.5334 0.254) (xy 0.635 0.254) (xy 0.635 0.2286) (xy 0.635 -0.254) (xy 0.5334 -0.254) (xy 0.5334 -0.2794)
				(xy -0.5334 -0.2794) (xy -0.5334 -0.254) (xy -0.635 -0.254) (xy -0.635 0.254) (xy -0.5334 0.254)
				(xy -0.5334 0.2794) (xy 0.508 0.2794) (xy 0.5334 0.2794)
			)
			(stroke
				(width 0)
				(type default)
			)
			(fill no)
			(layer "B.CrtYd")
		)
		(pad "1" smd rect
			(at -0.40005 0)
			(size 0.4572 0.508)
			(layers "B.Cu" "B.Mask" "B.Paste")
			(net "P3V3_NODE1")
		)
		(pad "2" smd rect
			(at 0.40005 0)
			(size 0.4572 0.508)
			(layers "B.Cu" "B.Mask" "B.Paste")
			(net "GND")
		)
	)
	(footprint ""
		(layer "B.Cu")
		(at 117.45976 -188.126624 -90)
		(property "Reference" "C644"
			(at -4.080256 -0.814578 270)
			(unlocked yes)
			(layer "B.SilkS")
			(effects
				(font
					(size 0.7874 0.5842)
					(thickness 0.1524)
				)
				(justify left mirror)
			)
		)
		(property "Value" ""
			(at 0 0 90)
			(layer "B.Fab")
			(effects
				(font
					(size 1.27 1.27)
				)
				(justify mirror)
			)
		)
		(duplicate_pad_numbers_are_jumpers no)
		(fp_line
			(start -0.7874 0.4064)
			(end 0.7874 0.4064)
			(stroke
				(width 0.1524)
				(type default)
			)
			(layer "B.SilkS")
		)
		(fp_line
			(start 0.7874 0.4064)
			(end 0.7874 -0.4064)
			(stroke
				(width 0.1524)
				(type default)
			)
			(layer "B.SilkS")
		)
		(fp_line
			(start 0 0.381)
			(end 0 -0.381)
			(stroke
				(width 0.1524)
				(type default)
			)
			(layer "B.SilkS")
		)
		(fp_line
			(start -0.7874 -0.4064)
			(end -0.7874 0.4064)
			(stroke
				(width 0.1524)
				(type default)
			)
			(layer "B.SilkS")
		)
		(fp_line
			(start 0.7874 -0.4064)
			(end -0.7874 -0.4064)
			(stroke
				(width 0.1524)
				(type default)
			)
			(layer "B.SilkS")
		)
		(fp_poly
			(pts
				(xy 0.5334 0.254) (xy 0.635 0.254) (xy 0.635 0.2286) (xy 0.635 -0.254) (xy 0.5334 -0.254) (xy 0.5334 -0.2794)
				(xy -0.5334 -0.2794) (xy -0.5334 -0.254) (xy -0.635 -0.254) (xy -0.635 0.254) (xy -0.5334 0.254)
				(xy -0.5334 0.2794) (xy 0.508 0.2794) (xy 0.5334 0.2794)
			)
			(stroke
				(width 0)
				(type default)
			)
			(fill no)
			(layer "B.CrtYd")
		)
		(pad "1" smd rect
			(at -0.40005 0 90)
			(size 0.4572 0.508)
			(layers "B.Cu" "B.Mask" "B.Paste")
			(net "T7_NODE4_EN_R")
		)
		(pad "2" smd rect
			(at 0.40005 0 90)
			(size 0.4572 0.508)
			(layers "B.Cu" "B.Mask" "B.Paste")
			(net "GND")
		)
	)
	(footprint ""
		(layer "B.Cu")
		(at 122.860054 -32.106108 180)
		(property "Reference" "C487"
			(at 2.833624 -1.068324 0)
			(unlocked yes)
			(layer "B.SilkS")
			(effects
				(font
					(size 0.7874 0.5842)
					(thickness 0.1524)
				)
				(justify left mirror)
			)
		)
		(property "Value" ""
			(at 0 0 0)
			(layer "B.Fab")
			(effects
				(font
					(size 1.27 1.27)
				)
				(justify mirror)
			)
		)
		(duplicate_pad_numbers_are_jumpers no)
		(fp_line
			(start 0.7874 0.4064)
			(end 0.7874 -0.4064)
			(stroke
				(width 0.1524)
				(type default)
			)
			(layer "B.SilkS")
		)
		(fp_line
			(start 0.7874 -0.4064)
			(end -0.7874 -0.4064)
			(stroke
				(width 0.1524)
				(type default)
			)
			(layer "B.SilkS")
		)
		(fp_line
			(start 0 0.381)
			(end 0 -0.381)
			(stroke
				(width 0.1524)
				(type default)
			)
			(layer "B.SilkS")
		)
		(fp_line
			(start -0.7874 0.4064)
			(end 0.7874 0.4064)
			(stroke
				(width 0.1524)
				(type default)
			)
			(layer "B.SilkS")
		)
		(fp_line
			(start -0.7874 -0.4064)
			(end -0.7874 0.4064)
			(stroke
				(width 0.1524)
				(type default)
			)
			(layer "B.SilkS")
		)
		(fp_poly
			(pts
				(xy 0.5334 0.254) (xy 0.635 0.254) (xy 0.635 0.2286) (xy 0.635 -0.254) (xy 0.5334 -0.254) (xy 0.5334 -0.2794)
				(xy -0.5334 -0.2794) (xy -0.5334 -0.254) (xy -0.635 -0.254) (xy -0.635 0.254) (xy -0.5334 0.254)
				(xy -0.5334 0.2794) (xy 0.508 0.2794) (xy 0.5334 0.2794)
			)
			(stroke
				(width 0)
				(type default)
			)
			(fill no)
			(layer "B.CrtYd")
		)
		(pad "1" smd rect
			(at -0.40005 0)
			(size 0.4572 0.508)
			(layers "B.Cu" "B.Mask" "B.Paste")
			(net "SIO_VCCH")
		)
		(pad "2" smd rect
			(at 0.40005 0)
			(size 0.4572 0.508)
			(layers "B.Cu" "B.Mask" "B.Paste")
			(net "GND")
		)
	)
)
